FILE_TYPE = MACRO_DRAWING;
SET COLOR_WIRE YELLOW;
SET COLOR_PROP ORANGE;
SET COLOR_DOT WHITE;
SET COLOR_ARC YELLOW;
SET COLOR_BODY GREEN;
SET COLOR_NOTE PURPLE;
SET PROP_DISPLAY VALUE;
SET PAGE_NUMBER P3;
FORCEADD QUANTA_TITLE_BLOCK_C..2
(-100 100);
FORCEPROP 1 LAST Q_TITLE TABLE OF CONTENT 2/3
J 0
(-9416 151);
DISPLAY 2.446809 (-9416 151);
PAINT GREEN (-9416 151);
FORCEPROP 1 LAST Q_DEPT BU9
J 1
(-3851 149);
DISPLAY 1.957447 (-3851 149);
PAINT GREEN (-3851 149);
FORCEPROP 1 LAST CUSTOM_TXT_CDS <CON_TC_SNO167>
J 2
(-5300 5075);
FORCEPROP 1 LAST CUSTOM_TXT_CDS <CON_TC_SNM172>
J 0
(-5200 4575);
FORCEPROP 1 LAST CUSTOM_TXT_CDS <CON_TC_SNM207>
J 0
(-2700 5075);
FORCEPROP 1 LAST CUSTOM_TXT_CDS <CON_TC_SNM206>
J 0
(-2700 5175);
FORCEPROP 1 LAST CUSTOM_TXT_CDS <CON_TC_SNM205>
J 0
(-2700 5275);
FORCEPROP 1 LAST CUSTOM_TXT_CDS <CON_TC_SNM202>
J 0
(-2700 5575);
FORCEPROP 2 LAST CUSTOM_TXT_CDS <NAME_1>
J 0
(-3300 275);
DISPLAY 1.021277 (-3300 275);
FORCEPROP 2 LAST CUSTOM_TXT_CDS <NAME_2>
J 0
(-3300 150);
DISPLAY 1.021277 (-3300 150);
FORCEPROP 1 LAST CUSTOM_TXT_CDS <CON_TC_SNO200>
J 2
(-5300 1775);
FORCEPROP 1 LAST CUSTOM_TXT_CDS <CON_TC_SNM149>
J 0
(-7700 2875);
FORCEPROP 1 LAST CUSTOM_TXT_CDS <CON_TC_SNO197>
J 2
(-5300 2075);
FORCEPROP 1 LAST CUSTOM_TXT_CDS <Q_NUMBER>
J 0
(-1500 200);
DISPLAY 1.212766 (-1500 200);
FORCEPROP 1 LAST CUSTOM_TXT_CDS <CON_LAST_MODIFIED>
J 0
(-2000 125);
DISPLAY 0.978723 (-2000 125);
FORCEPROP 1 LAST CUSTOM_TXT_CDS <Q_PROJ>
J 0
(-2475 200);
DISPLAY 1.212766 (-2475 200);
FORCEPROP 1 LAST CUSTOM_TXT_CDS <Q_REV>
J 0
(-275 200);
DISPLAY 1.212766 (-275 200);
FORCEPROP 1 LAST CUSTOM_TXT_CDS <CON_PAGE_NUM> OF <CON_TOTAL_PAGES>
J 0
(-538 113);
DISPLAY 0.978723 (-538 113);
FORCEPROP 1 LAST CUSTOM_TXT_CDS <CON_TC_SNM121>
J 0
(-7700 5675);
FORCEPROP 1 LAST CUSTOM_TXT_CDS <CON_TC_SNM122>
J 0
(-7700 5575);
FORCEPROP 1 LAST CUSTOM_TXT_CDS <CON_TC_SNM123>
J 0
(-7700 5475);
FORCEPROP 1 LAST CUSTOM_TXT_CDS <CON_TC_SNM124>
J 0
(-7700 5375);
FORCEPROP 1 LAST CUSTOM_TXT_CDS <CON_TC_SNM125>
J 0
(-7700 5275);
FORCEPROP 1 LAST CUSTOM_TXT_CDS <CON_TC_SNM126>
J 0
(-7700 5175);
FORCEPROP 1 LAST CUSTOM_TXT_CDS <CON_TC_SNM127>
J 0
(-7700 5075);
FORCEPROP 1 LAST CUSTOM_TXT_CDS <CON_TC_SNM128>
J 0
(-7700 4975);
FORCEPROP 1 LAST CUSTOM_TXT_CDS <CON_TC_SNM129>
J 0
(-7700 4875);
FORCEPROP 1 LAST CUSTOM_TXT_CDS <CON_TC_SNM130>
J 0
(-7700 4775);
FORCEPROP 1 LAST CUSTOM_TXT_CDS <CON_TC_SNM131>
J 0
(-7700 4675);
FORCEPROP 1 LAST CUSTOM_TXT_CDS <CON_TC_SNM132>
J 0
(-7700 4575);
FORCEPROP 1 LAST CUSTOM_TXT_CDS <CON_TC_SNM133>
J 0
(-7700 4475);
FORCEPROP 1 LAST CUSTOM_TXT_CDS <CON_TC_SNM134>
J 0
(-7700 4375);
FORCEPROP 1 LAST CUSTOM_TXT_CDS <CON_TC_SNM135>
J 0
(-7700 4275);
FORCEPROP 1 LAST CUSTOM_TXT_CDS <CON_TC_SNM136>
J 0
(-7700 4175);
FORCEPROP 1 LAST CUSTOM_TXT_CDS <CON_TC_SNM137>
J 0
(-7700 4075);
FORCEPROP 1 LAST CUSTOM_TXT_CDS <CON_TC_SNM138>
J 0
(-7700 3975);
FORCEPROP 1 LAST CUSTOM_TXT_CDS <CON_TC_SNM139>
J 0
(-7700 3875);
FORCEPROP 1 LAST CUSTOM_TXT_CDS <CON_TC_SNM140>
J 0
(-7700 3775);
FORCEPROP 1 LAST CUSTOM_TXT_CDS <CON_TC_SNM141>
J 0
(-7700 3675);
FORCEPROP 1 LAST CUSTOM_TXT_CDS <CON_TC_SNM142>
J 0
(-7700 3575);
FORCEPROP 1 LAST CUSTOM_TXT_CDS <CON_TC_SNM143>
J 0
(-7700 3475);
FORCEPROP 1 LAST CUSTOM_TXT_CDS <CON_TC_SNM144>
J 0
(-7700 3375);
FORCEPROP 1 LAST CUSTOM_TXT_CDS <CON_TC_SNM145>
J 0
(-7700 3275);
FORCEPROP 1 LAST CUSTOM_TXT_CDS <CON_TC_SNM146>
J 0
(-7700 3175);
FORCEPROP 1 LAST CUSTOM_TXT_CDS <CON_TC_SNM147>
J 0
(-7700 3075);
FORCEPROP 1 LAST CUSTOM_TXT_CDS <CON_TC_SNM148>
J 0
(-7700 2975);
FORCEPROP 1 LAST CUSTOM_TXT_CDS <CON_TC_SNM150>
J 0
(-7700 2775);
FORCEPROP 1 LAST CUSTOM_TXT_CDS <CON_TC_SNM151>
J 0
(-7700 2675);
FORCEPROP 1 LAST CUSTOM_TXT_CDS <CON_TC_SNM152>
J 0
(-7700 2575);
FORCEPROP 1 LAST CUSTOM_TXT_CDS <CON_TC_SNM153>
J 0
(-7700 2475);
FORCEPROP 1 LAST CUSTOM_TXT_CDS <CON_TC_SNM154>
J 0
(-7700 2375);
FORCEPROP 1 LAST CUSTOM_TXT_CDS <CON_TC_SNM155>
J 0
(-7700 2275);
FORCEPROP 1 LAST CUSTOM_TXT_CDS <CON_TC_SNM156>
J 0
(-7700 2175);
FORCEPROP 1 LAST CUSTOM_TXT_CDS <CON_TC_SNM157>
J 0
(-7700 2075);
FORCEPROP 1 LAST CUSTOM_TXT_CDS <CON_TC_SNM158>
J 0
(-7700 1975);
FORCEPROP 1 LAST CUSTOM_TXT_CDS <CON_TC_SNM159>
J 0
(-7700 1875);
FORCEPROP 1 LAST CUSTOM_TXT_CDS <CON_TC_SNM160>
J 0
(-7700 1775);
FORCEPROP 1 LAST CUSTOM_TXT_CDS <CON_TC_SNM161>
J 0
(-5200 5675);
FORCEPROP 1 LAST CUSTOM_TXT_CDS <CON_TC_SNM162>
J 0
(-5200 5575);
FORCEPROP 1 LAST CUSTOM_TXT_CDS <CON_TC_SNM163>
J 0
(-5200 5475);
FORCEPROP 1 LAST CUSTOM_TXT_CDS <CON_TC_SNM164>
J 0
(-5200 5375);
FORCEPROP 1 LAST CUSTOM_TXT_CDS <CON_TC_SNM165>
J 0
(-5200 5275);
FORCEPROP 1 LAST CUSTOM_TXT_CDS <CON_TC_SNM166>
J 0
(-5200 5175);
FORCEPROP 1 LAST CUSTOM_TXT_CDS <CON_TC_SNM167>
J 0
(-5200 5075);
FORCEPROP 1 LAST CUSTOM_TXT_CDS <CON_TC_SNM168>
J 0
(-5200 4975);
FORCEPROP 1 LAST CUSTOM_TXT_CDS <CON_TC_SNM169>
J 0
(-5200 4875);
FORCEPROP 1 LAST CUSTOM_TXT_CDS <CON_TC_SNM170>
J 0
(-5200 4775);
FORCEPROP 1 LAST CUSTOM_TXT_CDS <CON_TC_SNM171>
J 0
(-5200 4675);
FORCEPROP 1 LAST CUSTOM_TXT_CDS <CON_TC_SNM173>
J 0
(-5200 4475);
FORCEPROP 1 LAST CUSTOM_TXT_CDS <CON_TC_SNM174>
J 0
(-5200 4375);
FORCEPROP 1 LAST CUSTOM_TXT_CDS <CON_TC_SNM175>
J 0
(-5200 4275);
FORCEPROP 1 LAST CUSTOM_TXT_CDS <CON_TC_SNM176>
J 0
(-5200 4175);
FORCEPROP 1 LAST CUSTOM_TXT_CDS <CON_TC_SNM177>
J 0
(-5200 4075);
FORCEPROP 1 LAST CUSTOM_TXT_CDS <CON_TC_SNM178>
J 0
(-5200 3975);
FORCEPROP 1 LAST CUSTOM_TXT_CDS <CON_TC_SNM179>
J 0
(-5200 3875);
FORCEPROP 1 LAST CUSTOM_TXT_CDS <CON_TC_SNM180>
J 0
(-5200 3775);
FORCEPROP 1 LAST CUSTOM_TXT_CDS <CON_TC_SNM181>
J 0
(-5200 3675);
FORCEPROP 1 LAST CUSTOM_TXT_CDS <CON_TC_SNM182>
J 0
(-5200 3575);
FORCEPROP 1 LAST CUSTOM_TXT_CDS <CON_TC_SNM183>
J 0
(-5200 3475);
FORCEPROP 1 LAST CUSTOM_TXT_CDS <CON_TC_SNM184>
J 0
(-5200 3375);
FORCEPROP 1 LAST CUSTOM_TXT_CDS <CON_TC_SNM185>
J 0
(-5200 3275);
FORCEPROP 1 LAST CUSTOM_TXT_CDS <CON_TC_SNM186>
J 0
(-5200 3175);
FORCEPROP 1 LAST CUSTOM_TXT_CDS <CON_TC_SNM187>
J 0
(-5200 3075);
FORCEPROP 1 LAST CUSTOM_TXT_CDS <CON_TC_SNM188>
J 0
(-5200 2975);
FORCEPROP 1 LAST CUSTOM_TXT_CDS <CON_TC_SNM189>
J 0
(-5200 2875);
FORCEPROP 1 LAST CUSTOM_TXT_CDS <CON_TC_SNM190>
J 0
(-5200 2775);
FORCEPROP 1 LAST CUSTOM_TXT_CDS <CON_TC_SNM191>
J 0
(-5200 2675);
FORCEPROP 1 LAST CUSTOM_TXT_CDS <CON_TC_SNM192>
J 0
(-5200 2575);
FORCEPROP 1 LAST CUSTOM_TXT_CDS <CON_TC_SNM193>
J 0
(-5200 2475);
FORCEPROP 1 LAST CUSTOM_TXT_CDS <CON_TC_SNM194>
J 0
(-5200 2375);
FORCEPROP 1 LAST CUSTOM_TXT_CDS <CON_TC_SNM195>
J 0
(-5200 2275);
FORCEPROP 1 LAST CUSTOM_TXT_CDS <CON_TC_SNM196>
J 0
(-5200 2175);
FORCEPROP 1 LAST CUSTOM_TXT_CDS <CON_TC_SNM197>
J 0
(-5200 2075);
FORCEPROP 1 LAST CUSTOM_TXT_CDS <CON_TC_SNM198>
J 0
(-5200 1975);
FORCEPROP 1 LAST CUSTOM_TXT_CDS <CON_TC_SNM199>
J 0
(-5200 1875);
FORCEPROP 1 LAST CUSTOM_TXT_CDS <CON_TC_SNM200>
J 0
(-5200 1775);
FORCEPROP 1 LAST CUSTOM_TXT_CDS <CON_TC_SNM201>
J 0
(-2700 5675);
FORCEPROP 1 LAST CUSTOM_TXT_CDS <CON_TC_SNM203>
J 0
(-2700 5475);
FORCEPROP 1 LAST CUSTOM_TXT_CDS <CON_TC_SNM204>
J 0
(-2700 5375);
FORCEPROP 1 LAST CUSTOM_TXT_CDS <CON_TC_SNM208>
J 0
(-2700 4975);
FORCEPROP 1 LAST CUSTOM_TXT_CDS <CON_TC_SNM209>
J 0
(-2700 4875);
FORCEPROP 1 LAST CUSTOM_TXT_CDS <CON_TC_SNM210>
J 0
(-2700 4775);
FORCEPROP 1 LAST CUSTOM_TXT_CDS <CON_TC_SNM211>
J 0
(-2700 4675);
FORCEPROP 1 LAST CUSTOM_TXT_CDS <CON_TC_SNM212>
J 0
(-2700 4575);
FORCEPROP 1 LAST CUSTOM_TXT_CDS <CON_TC_SNM213>
J 0
(-2700 4475);
FORCEPROP 1 LAST CUSTOM_TXT_CDS <CON_TC_SNM214>
J 0
(-2700 4375);
FORCEPROP 1 LAST CUSTOM_TXT_CDS <CON_TC_SNM215>
J 0
(-2700 4275);
FORCEPROP 1 LAST CUSTOM_TXT_CDS <CON_TC_SNM216>
J 0
(-2700 4175);
FORCEPROP 1 LAST CUSTOM_TXT_CDS <CON_TC_SNM217>
J 0
(-2700 4075);
FORCEPROP 1 LAST CUSTOM_TXT_CDS <CON_TC_SNM218>
J 0
(-2700 3975);
FORCEPROP 1 LAST CUSTOM_TXT_CDS <CON_TC_SNM219>
J 0
(-2700 3875);
FORCEPROP 1 LAST CUSTOM_TXT_CDS <CON_TC_SNM220>
J 0
(-2700 3775);
FORCEPROP 1 LAST CUSTOM_TXT_CDS <CON_TC_SNM221>
J 0
(-2700 3675);
FORCEPROP 1 LAST CUSTOM_TXT_CDS <CON_TC_SNM222>
J 0
(-2700 3575);
FORCEPROP 1 LAST CUSTOM_TXT_CDS <CON_TC_SNM223>
J 0
(-2700 3475);
FORCEPROP 1 LAST CUSTOM_TXT_CDS <CON_TC_SNM224>
J 0
(-2700 3375);
FORCEPROP 1 LAST CUSTOM_TXT_CDS <CON_TC_SNM225>
J 0
(-2700 3275);
FORCEPROP 1 LAST CUSTOM_TXT_CDS <CON_TC_SNM226>
J 0
(-2700 3175);
FORCEPROP 1 LAST CUSTOM_TXT_CDS <CON_TC_SNM227>
J 0
(-2700 3075);
FORCEPROP 1 LAST CUSTOM_TXT_CDS <CON_TC_SNM228>
J 0
(-2700 2975);
FORCEPROP 1 LAST CUSTOM_TXT_CDS <CON_TC_SNM229>
J 0
(-2700 2875);
FORCEPROP 1 LAST CUSTOM_TXT_CDS <CON_TC_SNM230>
J 0
(-2700 2775);
FORCEPROP 1 LAST CUSTOM_TXT_CDS <CON_TC_SNM231>
J 0
(-2700 2675);
FORCEPROP 1 LAST CUSTOM_TXT_CDS <CON_TC_SNM232>
J 0
(-2700 2575);
FORCEPROP 1 LAST CUSTOM_TXT_CDS <CON_TC_SNM233>
J 0
(-2700 2475);
FORCEPROP 1 LAST CUSTOM_TXT_CDS <CON_TC_SNM234>
J 0
(-2700 2375);
FORCEPROP 1 LAST CUSTOM_TXT_CDS <CON_TC_SNM235>
J 0
(-2700 2275);
FORCEPROP 1 LAST CUSTOM_TXT_CDS <CON_TC_SNM236>
J 0
(-2700 2175);
FORCEPROP 1 LAST CUSTOM_TXT_CDS <CON_TC_SNM237>
J 0
(-2700 2075);
FORCEPROP 1 LAST CUSTOM_TXT_CDS <CON_TC_SNM238>
J 0
(-2700 1975);
FORCEPROP 1 LAST CUSTOM_TXT_CDS <CON_TC_SNM239>
J 0
(-2700 1875);
FORCEPROP 1 LAST CUSTOM_TXT_CDS <CON_TC_SNM240>
J 0
(-2700 1775);
FORCEPROP 1 LAST CUSTOM_TXT_CDS <CON_TC_SNO121>
J 2
(-7800 5675);
FORCEPROP 1 LAST CUSTOM_TXT_CDS <CON_TC_SNO122>
J 2
(-7800 5575);
FORCEPROP 1 LAST CUSTOM_TXT_CDS <CON_TC_SNO123>
J 2
(-7800 5475);
FORCEPROP 1 LAST CUSTOM_TXT_CDS <CON_TC_SNO124>
J 2
(-7800 5375);
FORCEPROP 1 LAST CUSTOM_TXT_CDS <CON_TC_SNO125>
J 2
(-7800 5275);
FORCEPROP 1 LAST CUSTOM_TXT_CDS <CON_TC_SNO126>
J 2
(-7800 5175);
FORCEPROP 1 LAST CUSTOM_TXT_CDS <CON_TC_SNO127>
J 2
(-7800 5075);
FORCEPROP 1 LAST CUSTOM_TXT_CDS <CON_TC_SNO128>
J 2
(-7800 4975);
FORCEPROP 1 LAST CUSTOM_TXT_CDS <CON_TC_SNO129>
J 2
(-7800 4875);
FORCEPROP 1 LAST CUSTOM_TXT_CDS <CON_TC_SNO130>
J 2
(-7800 4775);
FORCEPROP 1 LAST CUSTOM_TXT_CDS <CON_TC_SNO131>
J 2
(-7800 4675);
FORCEPROP 1 LAST CUSTOM_TXT_CDS <CON_TC_SNO132>
J 2
(-7800 4575);
FORCEPROP 1 LAST CUSTOM_TXT_CDS <CON_TC_SNO133>
J 2
(-7800 4475);
FORCEPROP 1 LAST CUSTOM_TXT_CDS <CON_TC_SNO134>
J 2
(-7800 4375);
FORCEPROP 1 LAST CUSTOM_TXT_CDS <CON_TC_SNO135>
J 2
(-7800 4275);
FORCEPROP 1 LAST CUSTOM_TXT_CDS <CON_TC_SNO136>
J 2
(-7800 4175);
FORCEPROP 1 LAST CUSTOM_TXT_CDS <CON_TC_SNO137>
J 2
(-7800 4075);
FORCEPROP 1 LAST CUSTOM_TXT_CDS <CON_TC_SNO138>
J 2
(-7800 3975);
FORCEPROP 1 LAST CUSTOM_TXT_CDS <CON_TC_SNO139>
J 2
(-7800 3875);
FORCEPROP 1 LAST CUSTOM_TXT_CDS <CON_TC_SNO140>
J 2
(-7800 3775);
FORCEPROP 1 LAST CUSTOM_TXT_CDS <CON_TC_SNO141>
J 2
(-7800 3675);
FORCEPROP 1 LAST CUSTOM_TXT_CDS <CON_TC_SNO142>
J 2
(-7800 3575);
FORCEPROP 1 LAST CUSTOM_TXT_CDS <CON_TC_SNO143>
J 2
(-7800 3475);
FORCEPROP 1 LAST CUSTOM_TXT_CDS <CON_TC_SNO144>
J 2
(-7800 3375);
FORCEPROP 1 LAST CUSTOM_TXT_CDS <CON_TC_SNO145>
J 2
(-7800 3275);
FORCEPROP 1 LAST CUSTOM_TXT_CDS <CON_TC_SNO146>
J 2
(-7800 3175);
FORCEPROP 1 LAST CUSTOM_TXT_CDS <CON_TC_SNO147>
J 2
(-7800 3075);
FORCEPROP 1 LAST CUSTOM_TXT_CDS <CON_TC_SNO148>
J 2
(-7800 2975);
FORCEPROP 1 LAST CUSTOM_TXT_CDS <CON_TC_SNO149>
J 2
(-7800 2875);
FORCEPROP 1 LAST CUSTOM_TXT_CDS <CON_TC_SNO150>
J 2
(-7800 2775);
FORCEPROP 1 LAST CUSTOM_TXT_CDS <CON_TC_SNO151>
J 2
(-7800 2675);
FORCEPROP 1 LAST CUSTOM_TXT_CDS <CON_TC_SNO152>
J 2
(-7800 2575);
FORCEPROP 1 LAST CUSTOM_TXT_CDS <CON_TC_SNO153>
J 2
(-7800 2475);
FORCEPROP 1 LAST CUSTOM_TXT_CDS <CON_TC_SNO154>
J 2
(-7800 2375);
FORCEPROP 1 LAST CUSTOM_TXT_CDS <CON_TC_SNO155>
J 2
(-7800 2275);
FORCEPROP 1 LAST CUSTOM_TXT_CDS <CON_TC_SNO156>
J 2
(-7800 2175);
FORCEPROP 1 LAST CUSTOM_TXT_CDS <CON_TC_SNO157>
J 2
(-7800 2075);
FORCEPROP 1 LAST CUSTOM_TXT_CDS <CON_TC_SNO158>
J 2
(-7800 1975);
FORCEPROP 1 LAST CUSTOM_TXT_CDS <CON_TC_SNO159>
J 2
(-7800 1875);
FORCEPROP 1 LAST CUSTOM_TXT_CDS <CON_TC_SNO160>
J 2
(-7800 1775);
FORCEPROP 1 LAST CUSTOM_TXT_CDS <CON_TC_SNO161>
J 2
(-5300 5675);
FORCEPROP 1 LAST CUSTOM_TXT_CDS <CON_TC_SNO162>
J 2
(-5300 5575);
FORCEPROP 1 LAST CUSTOM_TXT_CDS <CON_TC_SNO163>
J 2
(-5300 5475);
FORCEPROP 1 LAST CUSTOM_TXT_CDS <CON_TC_SNO164>
J 2
(-5300 5375);
FORCEPROP 1 LAST CUSTOM_TXT_CDS <CON_TC_SNO165>
J 2
(-5300 5275);
FORCEPROP 1 LAST CUSTOM_TXT_CDS <CON_TC_SNO166>
J 2
(-5300 5175);
FORCEPROP 1 LAST CUSTOM_TXT_CDS <CON_TC_SNO168>
J 2
(-5300 4975);
FORCEPROP 1 LAST CUSTOM_TXT_CDS <CON_TC_SNO169>
J 2
(-5300 4875);
FORCEPROP 1 LAST CUSTOM_TXT_CDS <CON_TC_SNO170>
J 2
(-5300 4775);
FORCEPROP 1 LAST CUSTOM_TXT_CDS <CON_TC_SNO171>
J 2
(-5300 4675);
FORCEPROP 1 LAST CUSTOM_TXT_CDS <CON_TC_SNO172>
J 2
(-5300 4575);
FORCEPROP 1 LAST CUSTOM_TXT_CDS <CON_TC_SNO173>
J 2
(-5300 4475);
FORCEPROP 1 LAST CUSTOM_TXT_CDS <CON_TC_SNO174>
J 2
(-5300 4375);
FORCEPROP 1 LAST CUSTOM_TXT_CDS <CON_TC_SNO175>
J 2
(-5300 4275);
FORCEPROP 1 LAST CUSTOM_TXT_CDS <CON_TC_SNO176>
J 2
(-5300 4175);
FORCEPROP 1 LAST CUSTOM_TXT_CDS <CON_TC_SNO177>
J 2
(-5300 4075);
FORCEPROP 1 LAST CUSTOM_TXT_CDS <CON_TC_SNO178>
J 2
(-5300 3975);
FORCEPROP 1 LAST CUSTOM_TXT_CDS <CON_TC_SNO179>
J 2
(-5300 3875);
FORCEPROP 1 LAST CUSTOM_TXT_CDS <CON_TC_SNO180>
J 2
(-5300 3775);
FORCEPROP 1 LAST CUSTOM_TXT_CDS <CON_TC_SNO181>
J 2
(-5300 3675);
FORCEPROP 1 LAST CUSTOM_TXT_CDS <CON_TC_SNO182>
J 2
(-5300 3575);
FORCEPROP 1 LAST CUSTOM_TXT_CDS <CON_TC_SNO183>
J 2
(-5300 3475);
FORCEPROP 1 LAST CUSTOM_TXT_CDS <CON_TC_SNO184>
J 2
(-5300 3375);
FORCEPROP 1 LAST CUSTOM_TXT_CDS <CON_TC_SNO185>
J 2
(-5300 3275);
FORCEPROP 1 LAST CUSTOM_TXT_CDS <CON_TC_SNO186>
J 2
(-5300 3175);
FORCEPROP 1 LAST CUSTOM_TXT_CDS <CON_TC_SNO187>
J 2
(-5300 3075);
FORCEPROP 1 LAST CUSTOM_TXT_CDS <CON_TC_SNO188>
J 2
(-5300 2975);
FORCEPROP 1 LAST CUSTOM_TXT_CDS <CON_TC_SNO189>
J 2
(-5300 2875);
FORCEPROP 1 LAST CUSTOM_TXT_CDS <CON_TC_SNO190>
J 2
(-5300 2775);
FORCEPROP 1 LAST CUSTOM_TXT_CDS <CON_TC_SNO191>
J 2
(-5300 2675);
FORCEPROP 1 LAST CUSTOM_TXT_CDS <CON_TC_SNO192>
J 2
(-5300 2575);
FORCEPROP 1 LAST CUSTOM_TXT_CDS <CON_TC_SNO193>
J 2
(-5300 2475);
FORCEPROP 1 LAST CUSTOM_TXT_CDS <CON_TC_SNO194>
J 2
(-5300 2375);
FORCEPROP 1 LAST CUSTOM_TXT_CDS <CON_TC_SNO195>
J 2
(-5300 2275);
FORCEPROP 1 LAST CUSTOM_TXT_CDS <CON_TC_SNO196>
J 2
(-5300 2175);
FORCEPROP 1 LAST CUSTOM_TXT_CDS <CON_TC_SNO198>
J 2
(-5300 1975);
FORCEPROP 1 LAST CUSTOM_TXT_CDS <CON_TC_SNO199>
J 2
(-5300 1875);
FORCEPROP 1 LAST CUSTOM_TXT_CDS <CON_TC_SNO201>
J 2
(-2800 5675);
FORCEPROP 1 LAST CUSTOM_TXT_CDS <CON_TC_SNO202>
J 2
(-2800 5575);
FORCEPROP 1 LAST CUSTOM_TXT_CDS <CON_TC_SNO203>
J 2
(-2800 5475);
FORCEPROP 1 LAST CUSTOM_TXT_CDS <CON_TC_SNO204>
J 2
(-2800 5375);
FORCEPROP 1 LAST CUSTOM_TXT_CDS <CON_TC_SNO205>
J 2
(-2800 5275);
FORCEPROP 1 LAST CUSTOM_TXT_CDS <CON_TC_SNO206>
J 2
(-2800 5175);
FORCEPROP 1 LAST CUSTOM_TXT_CDS <CON_TC_SNO207>
J 2
(-2800 5075);
FORCEPROP 1 LAST CUSTOM_TXT_CDS <CON_TC_SNO208>
J 2
(-2800 4975);
FORCEPROP 1 LAST CUSTOM_TXT_CDS <CON_TC_SNO209>
J 2
(-2800 4875);
FORCEPROP 1 LAST CUSTOM_TXT_CDS <CON_TC_SNO210>
J 2
(-2800 4775);
FORCEPROP 1 LAST CUSTOM_TXT_CDS <CON_TC_SNO211>
J 2
(-2800 4675);
FORCEPROP 1 LAST CUSTOM_TXT_CDS <CON_TC_SNO212>
J 2
(-2800 4575);
FORCEPROP 1 LAST CUSTOM_TXT_CDS <CON_TC_SNO213>
J 2
(-2800 4475);
FORCEPROP 1 LAST CUSTOM_TXT_CDS <CON_TC_SNO214>
J 2
(-2800 4375);
FORCEPROP 1 LAST CUSTOM_TXT_CDS <CON_TC_SNO215>
J 2
(-2800 4275);
FORCEPROP 1 LAST CUSTOM_TXT_CDS <CON_TC_SNO216>
J 2
(-2800 4175);
FORCEPROP 1 LAST CUSTOM_TXT_CDS <CON_TC_SNO217>
J 2
(-2800 4075);
FORCEPROP 1 LAST CUSTOM_TXT_CDS <CON_TC_SNO218>
J 2
(-2800 3975);
FORCEPROP 1 LAST CUSTOM_TXT_CDS <CON_TC_SNO219>
J 2
(-2800 3875);
FORCEPROP 1 LAST CUSTOM_TXT_CDS <CON_TC_SNO220>
J 2
(-2800 3775);
FORCEPROP 1 LAST CUSTOM_TXT_CDS <CON_TC_SNO221>
J 2
(-2800 3675);
FORCEPROP 1 LAST CUSTOM_TXT_CDS <CON_TC_SNO222>
J 2
(-2800 3575);
FORCEPROP 1 LAST CUSTOM_TXT_CDS <CON_TC_SNO223>
J 2
(-2800 3475);
FORCEPROP 1 LAST CUSTOM_TXT_CDS <CON_TC_SNO224>
J 2
(-2800 3375);
FORCEPROP 1 LAST CUSTOM_TXT_CDS <CON_TC_SNO225>
J 2
(-2800 3275);
FORCEPROP 1 LAST CUSTOM_TXT_CDS <CON_TC_SNO226>
J 2
(-2800 3175);
FORCEPROP 1 LAST CUSTOM_TXT_CDS <CON_TC_SNO227>
J 2
(-2800 3075);
FORCEPROP 1 LAST CUSTOM_TXT_CDS <CON_TC_SNO228>
J 2
(-2800 2975);
FORCEPROP 1 LAST CUSTOM_TXT_CDS <CON_TC_SNO229>
J 2
(-2800 2875);
FORCEPROP 1 LAST CUSTOM_TXT_CDS <CON_TC_SNO230>
J 2
(-2800 2775);
FORCEPROP 1 LAST CUSTOM_TXT_CDS <CON_TC_SNO231>
J 2
(-2800 2675);
FORCEPROP 1 LAST CUSTOM_TXT_CDS <CON_TC_SNO232>
J 2
(-2800 2575);
FORCEPROP 1 LAST CUSTOM_TXT_CDS <CON_TC_SNO233>
J 2
(-2800 2475);
FORCEPROP 1 LAST CUSTOM_TXT_CDS <CON_TC_SNO234>
J 2
(-2800 2375);
FORCEPROP 1 LAST CUSTOM_TXT_CDS <CON_TC_SNO235>
J 2
(-2800 2275);
FORCEPROP 1 LAST CUSTOM_TXT_CDS <CON_TC_SNO236>
J 2
(-2800 2175);
FORCEPROP 1 LAST CUSTOM_TXT_CDS <CON_TC_SNO237>
J 2
(-2800 2075);
FORCEPROP 1 LAST CUSTOM_TXT_CDS <CON_TC_SNO238>
J 2
(-2800 1975);
FORCEPROP 1 LAST CUSTOM_TXT_CDS <CON_TC_SNO239>
J 2
(-2800 1875);
FORCEPROP 1 LAST CUSTOM_TXT_CDS <CON_TC_SNO240>
J 2
(-2800 1775);
FORCEPROP 2 LAST CDS_LIB pure_quanta
J 0
(-100 100);
DISPLAY INVISIBLE (-100 100);
FORCEPROP 2 LAST PAGE_BORDER TRUE
J 0
(-7990 5350);
DISPLAY 0.638298 (-7990 5350);
PAINT PINK (-7990 5350);
DISPLAY INVISIBLE (-7990 5350);
FORCEPROP 1 LAST TOC_SYMBOL TRUE
J 0
(-9274 6552);
DISPLAY 0.978723 (-9274 6552);
PAINT GREEN (-9274 6552);
DISPLAY INVISIBLE (-9274 6552);
FORCEPROP 1 LAST COMMENT_BODY TRUE
J 0
(-1249 126);
DISPLAY 0.978723 (-1249 126);
PAINT GREEN (-1249 126);
DISPLAY INVISIBLE (-1249 126);
FORCEPROP 0 LAST CDS_CON_LAST_MODIFIED Mon Nov 15 20:05:00 2021
J 0
(-2000 125);
DISPLAY INVISIBLE (-2000 125);
FORCEPROP 2 LAST CDS_XR_PAGE_TITLE CR-3 : @T6G_MB_LIB.T6G(SCH_1):PAGE3
J 0
(-7990 5350);
DISPLAY 0.638298 (-7990 5350);
PAINT PINK (-7990 5350);
DISPLAY INVISIBLE (-7990 5350);
FORCEPROP 2 LAST CUSTOM_TXT_CDS <XR_PAGE_TITLE>
J 0
(-7990 5350);
DISPLAY 0.638298 (-7990 5350);
PAINT PINK (-7990 5350);
DISPLAY INVISIBLE (-7990 5350);
QUIT
